# T6G (Grand Teton) — schematic netlist excerpt (pin names and nets, part order shuffled) for the footprints in the layout excerpt that follows; sources: Cadence DE-HDL packaged netlist, KiCad conversion of 04192023_DAF0TMB3IC0_F0TG_MB_C_brd_V02_OCP.brd

R738  Q_RES  33 5% CHIP  pkg 0402LF  page 56 : A = SPI_CPU1_CLK ; B = SPI_CPU1_R_CLK
C342  Q_CAP  1UF 4V 20% X6S  pkg 0201  page 334 : A = P0V9_CPU1_RT_2D ; B = GND
PC340  Q_CAPP  470UF 2.5V 20% EMPTY  pkg SMLF  page 215 : A = PVDDCR_SOC_P1 ; B = GND

(kicad_pcb
	(version 20260206)
	(generator "pcbnew")
	(generator_version "10.0")
	(general
		(thickness 1.6)
		(legacy_teardrops no)
	)
	(paper "A4")
	(title_block
		(title "04192023_DAF0TMB3IC0_F0TG_MB_C_brd_V02_OCP.brd")
		(comment 1 "Grand Teton / footprints 7020-7022 of 8354")
	)
	(layers
		(0 "F.Cu" signal "TOP")
		(4 "In1.Cu" signal "GND")
		(6 "In2.Cu" signal "IN1")
		(8 "In3.Cu" signal "GND1")
		(10 "In4.Cu" signal "IN2")
		(12 "In5.Cu" signal "GND2")
		(14 "In6.Cu" signal "IN3")
		(16 "In7.Cu" signal "GND3")
		(18 "In8.Cu" signal "VCC")
		(20 "In9.Cu" signal "VCC1")
		(22 "In10.Cu" signal "GND4")
		(24 "In11.Cu" signal "IN4")
		(26 "In12.Cu" signal "GND5")
		(28 "In13.Cu" signal "IN5")
		(30 "In14.Cu" signal "GND6")
		(32 "In15.Cu" signal "IN6")
		(34 "In16.Cu" signal "GND7")
		(2 "B.Cu" signal "BOTTOM")
		(9 "F.Adhes" user "F.Adhesive")
		(11 "B.Adhes" user "B.Adhesive")
		(13 "F.Paste" user "Package Geometry/Pastemask Top")
		(15 "B.Paste" user "Package Geometry/Pastemask Bottom")
		(5 "F.SilkS" user "Ref Des/Silkscreen Top")
		(7 "B.SilkS" user "Ref Des/Silkscreen Bottom")
		(1 "F.Mask" user "Board Geometry/Soldermask Top")
		(3 "B.Mask" user "Board Geometry/Soldermask Bottom")
		(17 "Dwgs.User" user "User.Drawings")
		(19 "Cmts.User" user "User.Comments")
		(21 "Eco1.User" user "User.Eco1")
		(23 "Eco2.User" user "User.Eco2")
		(25 "Edge.Cuts" user "Board Geometry/Outline")
		(27 "Margin" user)
		(31 "F.CrtYd" user "Package Geometry/Place Bound Top")
		(29 "B.CrtYd" user "Package Geometry/Place Bound Bottom")
		(35 "F.Fab" user "Ref Des/Assembly Top")
		(33 "B.Fab" user "Ref Des/Assembly Bottom")
	)
	(footprint ""
		(layer "B.Cu")
		(at 128.171194 -171.930568 90)
		(property "Reference" "PC340"
			(at 5.751576 1.613154 270)
			(unlocked yes)
			(layer "B.SilkS")
			(effects
				(font
					(size 0.7874 0.5842)
					(thickness 0.1524)
				)
				(justify left mirror)
			)
		)
		(property "Value" ""
			(at 0 0 90)
			(layer "B.Fab")
			(effects
				(font
					(size 1.27 1.27)
				)
				(justify mirror)
			)
		)
		(duplicate_pad_numbers_are_jumpers no)
		(fp_line
			(start 4.533392 -2.249932)
			(end -4.533392 -2.249932)
			(stroke
				(width 0.1524)
				(type default)
			)
			(layer "B.SilkS")
		)
		(fp_line
			(start -4.533392 -2.249932)
			(end -4.533392 2.249932)
			(stroke
				(width 0.1524)
				(type default)
			)
			(layer "B.SilkS")
		)
		(fp_line
			(start 4.533392 2.249932)
			(end 4.533392 -2.249932)
			(stroke
				(width 0.1524)
				(type default)
			)
			(layer "B.SilkS")
		)
		(fp_line
			(start -4.533392 2.249932)
			(end 4.533392 2.249932)
			(stroke
				(width 0.1524)
				(type default)
			)
			(layer "B.SilkS")
		)
		(fp_rect
			(start 4.533392 -2.326132)
			(end 5.39242 2.326132)
			(stroke
				(width 0)
				(type default)
			)
			(fill yes)
			(layer "B.SilkS")
		)
		(fp_line
			(start 3.750056 -2.249932)
			(end -3.750056 -2.249932)
			(stroke
				(width 0.1)
				(type default)
			)
			(layer "B.Fab")
		)
		(fp_line
			(start -3.750056 -2.249932)
			(end -3.750056 2.249932)
			(stroke
				(width 0.1)
				(type default)
			)
			(layer "B.Fab")
		)
		(fp_line
			(start 3.750056 2.249932)
			(end 3.750056 -2.249932)
			(stroke
				(width 0.1)
				(type default)
			)
			(layer "B.Fab")
		)
		(fp_line
			(start -3.750056 2.249932)
			(end 3.750056 2.249932)
			(stroke
				(width 0.1)
				(type default)
			)
			(layer "B.Fab")
		)
		(fp_text user "-"
			(at -4.8514 -0.14605 90)
			(unlocked yes)
			(layer "B.SilkS")
			(effects
				(font
					(size 1.905 1.4224)
					(thickness 0.1524)
				)
				(justify left mirror)
			)
		)
		(fp_text user "+"
			(at 6.322314 0.786384 0)
			(unlocked yes)
			(layer "B.SilkS")
			(effects
				(font
					(size 1.905 1.4224)
					(thickness 0.1524)
				)
				(justify left mirror)
			)
		)
		(fp_text user "-"
			(at -4.8514 -0.14605 90)
			(unlocked yes)
			(layer "B.Fab")
			(effects
				(font
					(size 1.905 1.4224)
					(thickness 0.1524)
				)
				(justify left mirror)
			)
		)
		(fp_text user "+"
			(at 6.322314 0.786384 0)
			(unlocked yes)
			(layer "B.Fab")
			(effects
				(font
					(size 1.905 1.4224)
					(thickness 0.1524)
				)
				(justify left mirror)
			)
		)
		(pad "1" smd rect
			(at 3.199892 0 270)
			(size 2.413 2.8194)
			(layers "B.Cu" "B.Mask" "B.Paste")
			(net "PVDDCR_SOC_P1")
		)
		(pad "2" smd rect
			(at -3.199892 0 270)
			(size 2.413 2.8194)
			(layers "B.Cu" "B.Mask" "B.Paste")
			(net "GND")
		)
	)
	(footprint ""
		(layer "B.Cu")
		(at 91.919044 -390.909302 90)
		(property "Reference" "C342"
			(at 0 0 90)
			(layer "B.SilkS")
			(hide yes)
			(effects
				(font
					(size 1.27 1.27)
				)
				(justify mirror)
			)
		)
		(property "Value" ""
			(at 0 0 90)
			(layer "B.Fab")
			(effects
				(font
					(size 1.27 1.27)
				)
				(justify mirror)
			)
		)
		(duplicate_pad_numbers_are_jumpers no)
		(fp_line
			(start 0.299974 -0.150114)
			(end -0.299974 -0.150114)
			(stroke
				(width 0.1)
				(type default)
			)
			(layer "B.Fab")
		)
		(fp_line
			(start -0.299974 -0.150114)
			(end -0.299974 0.150114)
			(stroke
				(width 0.1)
				(type default)
			)
			(layer "B.Fab")
		)
		(fp_line
			(start 0.299974 0.150114)
			(end 0.299974 -0.150114)
			(stroke
				(width 0.1)
				(type default)
			)
			(layer "B.Fab")
		)
		(fp_line
			(start -0.299974 0.150114)
			(end 0.299974 0.150114)
			(stroke
				(width 0.1)
				(type default)
			)
			(layer "B.Fab")
		)
		(pad "1" smd rect
			(at 0.2667 0 270)
			(size 0.3048 0.381)
			(layers "B.Cu" "B.Mask" "B.Paste")
			(net "P0V9_CPU1_RT_2D")
		)
		(pad "2" smd rect
			(at -0.2667 0 270)
			(size 0.3048 0.381)
			(layers "B.Cu" "B.Mask" "B.Paste")
			(net "GND")
		)
	)
	(footprint ""
		(layer "B.Cu")
		(at 145.217134 -322.101972)
		(property "Reference" "R738"
			(at 0 0 0)
			(layer "B.SilkS")
			(hide yes)
			(effects
				(font
					(size 1.27 1.27)
				)
				(justify mirror)
			)
		)
		(property "Value" ""
			(at 0 0 0)
			(layer "B.Fab")
			(effects
				(font
					(size 1.27 1.27)
				)
				(justify mirror)
			)
		)
		(duplicate_pad_numbers_are_jumpers no)
		(fp_line
			(start -0.7874 -0.4064)
			(end -0.7874 0.4064)
			(stroke
				(width 0.1524)
				(type default)
			)
			(layer "B.SilkS")
		)
		(fp_line
			(start -0.7874 0.4064)
			(end 0.7874 0.4064)
			(stroke
				(width 0.1524)
				(type default)
			)
			(layer "B.SilkS")
		)
		(fp_line
			(start 0.7874 -0.4064)
			(end -0.7874 -0.4064)
			(stroke
				(width 0.1524)
				(type default)
			)
			(layer "B.SilkS")
		)
		(fp_line
			(start 0.7874 0.4064)
			(end 0.7874 -0.4064)
			(stroke
				(width 0.1524)
				(type default)
			)
			(layer "B.SilkS")
		)
		(fp_line
			(start -0.67945 -0.3048)
			(end -0.67945 0.3048)
			(stroke
				(width 0.1)
				(type default)
			)
			(layer "B.Fab")
		)
		(fp_line
			(start -0.67945 0.3048)
			(end -0.120396 0.3048)
			(stroke
				(width 0.1)
				(type default)
			)
			(layer "B.Fab")
		)
		(fp_line
			(start -0.12065 -0.3048)
			(end -0.67945 -0.3048)
			(stroke
				(width 0.1)
				(type default)
			)
			(layer "B.Fab")
		)
		(fp_line
			(start -0.12065 -0.2794)
			(end -0.12065 -0.3048)
			(stroke
				(width 0.1)
				(type default)
			)
			(layer "B.Fab")
		)
		(fp_line
			(start -0.120396 0.2794)
			(end 0.12065 0.2794)
			(stroke
				(width 0.1)
				(type default)
			)
			(layer "B.Fab")
		)
		(fp_line
			(start -0.120396 0.3048)
			(end -0.120396 0.2794)
			(stroke
				(width 0.1)
				(type default)
			)
			(layer "B.Fab")
		)
		(fp_line
			(start 0.12065 -0.305054)
			(end 0.12065 -0.2794)
			(stroke
				(width 0.1)
				(type default)
			)
			(layer "B.Fab")
		)
		(fp_line
			(start 0.12065 -0.2794)
			(end -0.12065 -0.2794)
			(stroke
				(width 0.1)
				(type default)
			)
			(layer "B.Fab")
		)
		(fp_line
			(start 0.12065 0.2794)
			(end 0.12065 0.3048)
			(stroke
				(width 0.1)
				(type default)
			)
			(layer "B.Fab")
		)
		(fp_line
			(start 0.12065 0.3048)
			(end 0.67945 0.3048)
			(stroke
				(width 0.1)
				(type default)
			)
			(layer "B.Fab")
		)
		(fp_line
			(start 0.67945 -0.305054)
			(end 0.12065 -0.305054)
			(stroke
				(width 0.1)
				(type default)
			)
			(layer "B.Fab")
		)
		(fp_line
			(start 0.67945 0.3048)
			(end 0.67945 -0.305054)
			(stroke
				(width 0.1)
				(type default)
			)
			(layer "B.Fab")
		)
		(pad "1" smd circle
			(at 0.40005 0 180)
			(size 0 0)
			(layers "B.Cu" "B.Mask" "B.Paste")
			(net "SPI_CPU1_CLK")
		)
		(pad "2" smd circle
			(at -0.40005 0 180)
			(size 0 0)
			(layers "B.Cu" "B.Mask" "B.Paste")
			(net "SPI_CPU1_R_CLK")
		)
	)
)
